(kicad_pcb
	(version 20260206)
	(generator "pcbnew")
	(generator_version "10.0")
	(general
		(thickness 1.6)
		(legacy_teardrops no)
	)
	(paper "A4")
	(title_block
		(title "panther-plus-userver — 13130-1b_20150205.brd")
		(comment 1 "Honey Badger (Wiwynn) / footprint 1214 of 1509 (DIMM3), pads 100-106 of 210")
	)
	(layers
		(0 "F.Cu" signal "TOP")
		(4 "In1.Cu" signal "L2")
		(6 "In2.Cu" signal "L3")
		(8 "In3.Cu" signal "L4")
		(10 "In4.Cu" signal "L5")
		(12 "In5.Cu" signal "L6")
		(14 "In6.Cu" signal "L7")
		(16 "In7.Cu" signal "L8")
		(18 "In8.Cu" signal "L9")
		(20 "In9.Cu" signal "L10")
		(22 "In10.Cu" signal "L11")
		(2 "B.Cu" signal "BOTTOM")
		(9 "F.Adhes" user "F.Adhesive")
		(11 "B.Adhes" user "B.Adhesive")
		(13 "F.Paste" user "Package Geometry/Pastemask Top")
		(15 "B.Paste" user "Package Geometry/Pastemask Bottom")
		(5 "F.SilkS" user "Ref Des/Silkscreen Top")
		(7 "B.SilkS" user "Ref Des/Silkscreen Bottom")
		(1 "F.Mask" user "Board Geometry/Soldermask Top")
		(3 "B.Mask" user "Board Geometry/Soldermask Bottom")
		(17 "Dwgs.User" user "User.Drawings")
		(19 "Cmts.User" user "User.Comments")
		(21 "Eco1.User" user "User.Eco1")
		(23 "Eco2.User" user "User.Eco2")
		(25 "Edge.Cuts" user "Board Geometry/Outline")
		(27 "Margin" user)
		(31 "F.CrtYd" user "Package Geometry/Place Bound Top")
		(29 "B.CrtYd" user "Package Geometry/Place Bound Bottom")
		(35 "F.Fab" user "Ref Des/Assembly Top")
		(33 "B.Fab" user "Ref Des/Assembly Bottom")
	)
	(footprint ""
		(layer "B.Cu")
		(at 159.999934 -5.790692)
		(property "Reference" "DIMM3"
			(at 0 0 0)
			(layer "B.SilkS")
			(hide yes)
			(effects
				(font
					(size 1.27 1.27)
				)
				(justify mirror)
			)
		)
		(property "Value" "DDR3-204P-142-COLAY-1-GP-U"
			(at 41.312338 -16.676878 0)
			(unlocked yes)
			(layer "B.Fab")
			(hide yes)
			(effects
				(font
					(size 1.016 1.016)
					(thickness 0.1524)
				)
				(justify mirror)
			)
		)
		(property "Device Type" "AS0A626-J8R6-7H-COLAY-1"
			(at 41.312338 -18.200878 0)
			(unlocked yes)
			(layer "B.Fab")
			(hide yes)
			(effects
				(font
					(size 1.016 1.016)
					(thickness 0.1524)
				)
				(justify mirror)
			)
		)
		(duplicate_pad_numbers_are_jumpers no)
		(pad "98" smd custom
			(at -0.150114 4.100068 180)
			(size 0.1143 0.1143)
			(layers "B.Cu" "B.Mask" "B.Paste")
			(net "M_B_MA7")
			(options
				(clearance outline)
				(anchor circle)
			)
			(primitives
				(gr_poly
					(pts
						(xy 0 -0.9017) (xy -0.03175 -0.89916) (xy -0.0635 -0.889) (xy -0.09144 -0.87376) (xy -0.11684 -0.85344)
						(xy -0.13716 -0.82804) (xy -0.1524 -0.8001) (xy -0.16256 -0.76835) (xy -0.1651 -0.7366) (xy -0.1651 0.13462)
						(xy -0.17272 0.14224) (xy -0.19812 0.1778) (xy -0.2032 0.18796) (xy -0.20701 0.19685) (xy -0.21209 0.20701)
						(xy -0.2159 0.21717) (xy -0.21844 0.22733) (xy -0.22225 0.23876) (xy -0.22352 0.24892) (xy -0.22606 0.25908)
						(xy -0.22733 0.27051) (xy -0.22733 0.28067) (xy -0.2286 0.2921) (xy -0.22733 0.30353) (xy -0.22733 0.31369)
						(xy -0.22606 0.32512) (xy -0.22352 0.33528) (xy -0.22225 0.34544) (xy -0.21844 0.35687) (xy -0.2159 0.36703)
						(xy -0.21209 0.37719) (xy -0.20701 0.38735) (xy -0.2032 0.39624) (xy -0.19812 0.4064) (xy -0.17272 0.44196)
						(xy -0.1651 0.44958) (xy -0.1651 0.7366) (xy -0.16256 0.76835) (xy -0.1524 0.8001) (xy -0.13716 0.82804)
						(xy -0.11684 0.85344) (xy -0.09144 0.87376) (xy -0.0635 0.889) (xy -0.03175 0.89916) (xy 0 0.9017)
						(xy 0.03175 0.89916) (xy 0.0635 0.889) (xy 0.09144 0.87376) (xy 0.11684 0.85344) (xy 0.13716 0.82804)
						(xy 0.1524 0.8001) (xy 0.16256 0.76835) (xy 0.1651 0.7366) (xy 0.1651 0.44958) (xy 0.17272 0.44196)
						(xy 0.19812 0.4064) (xy 0.2032 0.39624) (xy 0.20701 0.38735) (xy 0.21209 0.37719) (xy 0.2159 0.36703)
						(xy 0.21844 0.35687) (xy 0.22225 0.34544) (xy 0.22352 0.33528) (xy 0.22606 0.32512) (xy 0.22733 0.31369)
						(xy 0.22733 0.30353) (xy 0.2286 0.2921) (xy 0.22733 0.28067) (xy 0.22733 0.27051) (xy 0.22606 0.25908)
						(xy 0.22352 0.24892) (xy 0.22225 0.23876) (xy 0.21844 0.22733) (xy 0.2159 0.21717) (xy 0.21209 0.20701)
						(xy 0.20701 0.19685) (xy 0.2032 0.18796) (xy 0.19812 0.1778) (xy 0.17272 0.14224) (xy 0.1651 0.13462)
						(xy 0.1651 -0.7366) (xy 0.16256 -0.76835) (xy 0.1524 -0.8001) (xy 0.13716 -0.82804) (xy 0.11684 -0.85344)
						(xy 0.09144 -0.87376) (xy 0.0635 -0.889) (xy 0.03175 -0.89916)
					)
					(width 0)
					(fill yes)
				)
			)
		)
		(pad "99" smd custom
			(at 0.150114 -4.100068 180)
			(size 0.1143 0.1143)
			(layers "B.Cu" "B.Mask" "B.Paste")
			(net "M_B_MA5")
			(options
				(clearance outline)
				(anchor circle)
			)
			(primitives
				(gr_poly
					(pts
						(xy 0 -0.9017) (xy -0.03175 -0.89916) (xy -0.0635 -0.889) (xy -0.09144 -0.87376) (xy -0.11684 -0.85344)
						(xy -0.13716 -0.82804) (xy -0.1524 -0.8001) (xy -0.16256 -0.76835) (xy -0.1651 -0.7366) (xy -0.1651 -0.19685)
						(xy -0.17272 -0.18923) (xy -0.17907 -0.18034) (xy -0.18669 -0.17145) (xy -0.19177 -0.16256) (xy -0.19812 -0.15367)
						(xy -0.20828 -0.13335) (xy -0.21971 -0.10287) (xy -0.22225 -0.09271) (xy -0.22479 -0.08128) (xy -0.22606 -0.07112)
						(xy -0.2286 -0.05969) (xy -0.2286 -0.01651) (xy -0.22606 -0.00508) (xy -0.22479 0.00508) (xy -0.22225 0.01651)
						(xy -0.21971 0.02667) (xy -0.20828 0.05715) (xy -0.19812 0.07747) (xy -0.19177 0.08636) (xy -0.18669 0.09525)
						(xy -0.17907 0.10414) (xy -0.17272 0.11303) (xy -0.1651 0.12065) (xy -0.1651 0.7366) (xy -0.16256 0.76835)
						(xy -0.1524 0.8001) (xy -0.13716 0.82804) (xy -0.11684 0.85344) (xy -0.09144 0.87376) (xy -0.0635 0.889)
						(xy -0.03175 0.89916) (xy 0 0.9017) (xy 0.03175 0.89916) (xy 0.0635 0.889) (xy 0.09144 0.87376)
						(xy 0.11684 0.85344) (xy 0.13716 0.82804) (xy 0.1524 0.8001) (xy 0.16256 0.76835) (xy 0.1651 0.7366)
						(xy 0.1651 0.11938) (xy 0.17272 0.11176) (xy 0.19812 0.0762) (xy 0.2032 0.06604) (xy 0.20701 0.05715)
						(xy 0.21209 0.04699) (xy 0.2159 0.03683) (xy 0.21844 0.02667) (xy 0.22225 0.01524) (xy 0.22352 0.00508)
						(xy 0.22606 -0.00508) (xy 0.22733 -0.01651) (xy 0.22733 -0.02667) (xy 0.2286 -0.0381) (xy 0.22733 -0.04953)
						(xy 0.22733 -0.05969) (xy 0.22606 -0.07112) (xy 0.22352 -0.08128) (xy 0.22225 -0.09144) (xy 0.21844 -0.10287)
						(xy 0.2159 -0.11303) (xy 0.21209 -0.12319) (xy 0.20701 -0.13335) (xy 0.2032 -0.14224) (xy 0.19812 -0.1524)
						(xy 0.17272 -0.18796) (xy 0.1651 -0.19558) (xy 0.1651 -0.7366) (xy 0.16256 -0.76835) (xy 0.1524 -0.8001)
						(xy 0.13716 -0.82804) (xy 0.11684 -0.85344) (xy 0.09144 -0.87376) (xy 0.0635 -0.889) (xy 0.03175 -0.89916)
					)
					(width 0)
					(fill yes)
				)
			)
		)
		(pad "100" smd custom
			(at 0.450088 4.100068 180)
			(size 0.1143 0.1143)
			(layers "B.Cu" "B.Mask" "B.Paste")
			(net "M_B_MA6")
			(options
				(clearance outline)
				(anchor circle)
			)
			(primitives
				(gr_poly
					(pts
						(xy 0 -0.9017) (xy -0.03175 -0.89916) (xy -0.0635 -0.889) (xy -0.09144 -0.87376) (xy -0.11684 -0.85344)
						(xy -0.13716 -0.82804) (xy -0.1524 -0.8001) (xy -0.16256 -0.76835) (xy -0.1651 -0.7366) (xy -0.1651 -0.11938)
						(xy -0.17272 -0.11176) (xy -0.19812 -0.0762) (xy -0.2032 -0.06604) (xy -0.20701 -0.05715) (xy -0.21209 -0.04699)
						(xy -0.2159 -0.03683) (xy -0.21844 -0.02667) (xy -0.22225 -0.01524) (xy -0.22352 -0.00508) (xy -0.22606 0.00508)
						(xy -0.22733 0.01651) (xy -0.22733 0.02667) (xy -0.2286 0.0381) (xy -0.22733 0.04953) (xy -0.22733 0.05969)
						(xy -0.22606 0.07112) (xy -0.22352 0.08128) (xy -0.22225 0.09144) (xy -0.21844 0.10287) (xy -0.2159 0.11303)
						(xy -0.21209 0.12319) (xy -0.20701 0.13335) (xy -0.2032 0.14224) (xy -0.19812 0.1524) (xy -0.17272 0.18796)
						(xy -0.1651 0.19558) (xy -0.1651 0.7366) (xy -0.16256 0.76835) (xy -0.1524 0.8001) (xy -0.13716 0.82804)
						(xy -0.11684 0.85344) (xy -0.09144 0.87376) (xy -0.0635 0.889) (xy -0.03175 0.89916) (xy 0 0.9017)
						(xy 0.03175 0.89916) (xy 0.0635 0.889) (xy 0.09144 0.87376) (xy 0.11684 0.85344) (xy 0.13716 0.82804)
						(xy 0.1524 0.8001) (xy 0.16256 0.76835) (xy 0.1651 0.7366) (xy 0.1651 0.19685) (xy 0.17272 0.18923)
						(xy 0.17907 0.18034) (xy 0.18669 0.17145) (xy 0.19177 0.16256) (xy 0.19812 0.15367) (xy 0.20828 0.13335)
						(xy 0.21971 0.10287) (xy 0.22225 0.09271) (xy 0.22479 0.08128) (xy 0.22606 0.07112) (xy 0.2286 0.05969)
						(xy 0.2286 0.01651) (xy 0.22606 0.00508) (xy 0.22479 -0.00508) (xy 0.22225 -0.01651) (xy 0.21971 -0.02667)
						(xy 0.20828 -0.05715) (xy 0.19812 -0.07747) (xy 0.19177 -0.08636) (xy 0.18669 -0.09525) (xy 0.17907 -0.10414)
						(xy 0.17272 -0.11303) (xy 0.1651 -0.12065) (xy 0.1651 -0.7366) (xy 0.16256 -0.76835) (xy 0.1524 -0.8001)
						(xy 0.13716 -0.82804) (xy 0.11684 -0.85344) (xy 0.09144 -0.87376) (xy 0.0635 -0.889) (xy 0.03175 -0.89916)
					)
					(width 0)
					(fill yes)
				)
			)
		)
		(pad "101" smd custom
			(at 0.750062 -4.100068 180)
			(size 0.1143 0.1143)
			(layers "B.Cu" "B.Mask" "B.Paste")
			(net "PV_VDDR")
			(options
				(clearance outline)
				(anchor circle)
			)
			(primitives
				(gr_poly
					(pts
						(xy 0 -0.9017) (xy -0.03175 -0.89916) (xy -0.0635 -0.889) (xy -0.09144 -0.87376) (xy -0.11684 -0.85344)
						(xy -0.13716 -0.82804) (xy -0.1524 -0.8001) (xy -0.16256 -0.76835) (xy -0.1651 -0.7366) (xy -0.1651 -0.44958)
						(xy -0.17272 -0.44196) (xy -0.19812 -0.4064) (xy -0.2032 -0.39624) (xy -0.20701 -0.38735) (xy -0.21209 -0.37719)
						(xy -0.2159 -0.36703) (xy -0.21844 -0.35687) (xy -0.22225 -0.34544) (xy -0.22352 -0.33528) (xy -0.22606 -0.32512)
						(xy -0.22733 -0.31369) (xy -0.22733 -0.30353) (xy -0.2286 -0.2921) (xy -0.22733 -0.28067) (xy -0.22733 -0.27051)
						(xy -0.22606 -0.25908) (xy -0.22352 -0.24892) (xy -0.22225 -0.23876) (xy -0.21844 -0.22733) (xy -0.2159 -0.21717)
						(xy -0.21209 -0.20701) (xy -0.20701 -0.19685) (xy -0.2032 -0.18796) (xy -0.19812 -0.1778) (xy -0.17272 -0.14224)
						(xy -0.1651 -0.13462) (xy -0.1651 0.7366) (xy -0.16256 0.76835) (xy -0.1524 0.8001) (xy -0.13716 0.82804)
						(xy -0.11684 0.85344) (xy -0.09144 0.87376) (xy -0.0635 0.889) (xy -0.03175 0.89916) (xy 0 0.9017)
						(xy 0.03175 0.89916) (xy 0.0635 0.889) (xy 0.09144 0.87376) (xy 0.11684 0.85344) (xy 0.13716 0.82804)
						(xy 0.1524 0.8001) (xy 0.16256 0.76835) (xy 0.1651 0.7366) (xy 0.1651 -0.13462) (xy 0.17272 -0.14224)
						(xy 0.19812 -0.1778) (xy 0.2032 -0.18796) (xy 0.20701 -0.19685) (xy 0.21209 -0.20701) (xy 0.2159 -0.21717)
						(xy 0.21844 -0.22733) (xy 0.22225 -0.23876) (xy 0.22352 -0.24892) (xy 0.22606 -0.25908) (xy 0.22733 -0.27051)
						(xy 0.22733 -0.28067) (xy 0.2286 -0.2921) (xy 0.22733 -0.30353) (xy 0.22733 -0.31369) (xy 0.22606 -0.32512)
						(xy 0.22352 -0.33528) (xy 0.22225 -0.34544) (xy 0.21844 -0.35687) (xy 0.2159 -0.36703) (xy 0.21209 -0.37719)
						(xy 0.20701 -0.38735) (xy 0.2032 -0.39624) (xy 0.19812 -0.4064) (xy 0.17272 -0.44196) (xy 0.1651 -0.44958)
						(xy 0.1651 -0.7366) (xy 0.16256 -0.76835) (xy 0.1524 -0.8001) (xy 0.13716 -0.82804) (xy 0.11684 -0.85344)
						(xy 0.09144 -0.87376) (xy 0.0635 -0.889) (xy 0.03175 -0.89916)
					)
					(width 0)
					(fill yes)
				)
			)
		)
		(pad "102" smd custom
			(at 1.050036 4.100068 180)
			(size 0.1143 0.1143)
			(layers "B.Cu" "B.Mask" "B.Paste")
			(net "PV_VDDR")
			(options
				(clearance outline)
				(anchor circle)
			)
			(primitives
				(gr_poly
					(pts
						(xy 0 -0.9017) (xy -0.03175 -0.89916) (xy -0.0635 -0.889) (xy -0.09144 -0.87376) (xy -0.11684 -0.85344)
						(xy -0.13716 -0.82804) (xy -0.1524 -0.8001) (xy -0.16256 -0.76835) (xy -0.1651 -0.7366) (xy -0.1651 0.13462)
						(xy -0.17272 0.14224) (xy -0.19812 0.1778) (xy -0.2032 0.18796) (xy -0.20701 0.19685) (xy -0.21209 0.20701)
						(xy -0.2159 0.21717) (xy -0.21844 0.22733) (xy -0.22225 0.23876) (xy -0.22352 0.24892) (xy -0.22606 0.25908)
						(xy -0.22733 0.27051) (xy -0.22733 0.28067) (xy -0.2286 0.2921) (xy -0.22733 0.30353) (xy -0.22733 0.31369)
						(xy -0.22606 0.32512) (xy -0.22352 0.33528) (xy -0.22225 0.34544) (xy -0.21844 0.35687) (xy -0.2159 0.36703)
						(xy -0.21209 0.37719) (xy -0.20701 0.38735) (xy -0.2032 0.39624) (xy -0.19812 0.4064) (xy -0.17272 0.44196)
						(xy -0.1651 0.44958) (xy -0.1651 0.7366) (xy -0.16256 0.76835) (xy -0.1524 0.8001) (xy -0.13716 0.82804)
						(xy -0.11684 0.85344) (xy -0.09144 0.87376) (xy -0.0635 0.889) (xy -0.03175 0.89916) (xy 0 0.9017)
						(xy 0.03175 0.89916) (xy 0.0635 0.889) (xy 0.09144 0.87376) (xy 0.11684 0.85344) (xy 0.13716 0.82804)
						(xy 0.1524 0.8001) (xy 0.16256 0.76835) (xy 0.1651 0.7366) (xy 0.1651 0.44958) (xy 0.17272 0.44196)
						(xy 0.19812 0.4064) (xy 0.2032 0.39624) (xy 0.20701 0.38735) (xy 0.21209 0.37719) (xy 0.2159 0.36703)
						(xy 0.21844 0.35687) (xy 0.22225 0.34544) (xy 0.22352 0.33528) (xy 0.22606 0.32512) (xy 0.22733 0.31369)
						(xy 0.22733 0.30353) (xy 0.2286 0.2921) (xy 0.22733 0.28067) (xy 0.22733 0.27051) (xy 0.22606 0.25908)
						(xy 0.22352 0.24892) (xy 0.22225 0.23876) (xy 0.21844 0.22733) (xy 0.2159 0.21717) (xy 0.21209 0.20701)
						(xy 0.20701 0.19685) (xy 0.2032 0.18796) (xy 0.19812 0.1778) (xy 0.17272 0.14224) (xy 0.1651 0.13462)
						(xy 0.1651 -0.7366) (xy 0.16256 -0.76835) (xy 0.1524 -0.8001) (xy 0.13716 -0.82804) (xy 0.11684 -0.85344)
						(xy 0.09144 -0.87376) (xy 0.0635 -0.889) (xy 0.03175 -0.89916)
					)
					(width 0)
					(fill yes)
				)
			)
		)
		(pad "103" smd custom
			(at 1.35001 -4.100068 180)
			(size 0.1143 0.1143)
			(layers "B.Cu" "B.Mask" "B.Paste")
			(net "M_B_MA3")
			(options
				(clearance outline)
				(anchor circle)
			)
			(primitives
				(gr_poly
					(pts
						(xy 0 -0.9017) (xy -0.03175 -0.89916) (xy -0.0635 -0.889) (xy -0.09144 -0.87376) (xy -0.11684 -0.85344)
						(xy -0.13716 -0.82804) (xy -0.1524 -0.8001) (xy -0.16256 -0.76835) (xy -0.1651 -0.7366) (xy -0.1651 -0.19685)
						(xy -0.17272 -0.18923) (xy -0.17907 -0.18034) (xy -0.18669 -0.17145) (xy -0.19177 -0.16256) (xy -0.19812 -0.15367)
						(xy -0.20828 -0.13335) (xy -0.21971 -0.10287) (xy -0.22225 -0.09271) (xy -0.22479 -0.08128) (xy -0.22606 -0.07112)
						(xy -0.2286 -0.05969) (xy -0.2286 -0.01651) (xy -0.22606 -0.00508) (xy -0.22479 0.00508) (xy -0.22225 0.01651)
						(xy -0.21971 0.02667) (xy -0.20828 0.05715) (xy -0.19812 0.07747) (xy -0.19177 0.08636) (xy -0.18669 0.09525)
						(xy -0.17907 0.10414) (xy -0.17272 0.11303) (xy -0.1651 0.12065) (xy -0.1651 0.7366) (xy -0.16256 0.76835)
						(xy -0.1524 0.8001) (xy -0.13716 0.82804) (xy -0.11684 0.85344) (xy -0.09144 0.87376) (xy -0.0635 0.889)
						(xy -0.03175 0.89916) (xy 0 0.9017) (xy 0.03175 0.89916) (xy 0.0635 0.889) (xy 0.09144 0.87376)
						(xy 0.11684 0.85344) (xy 0.13716 0.82804) (xy 0.1524 0.8001) (xy 0.16256 0.76835) (xy 0.1651 0.7366)
						(xy 0.1651 0.11938) (xy 0.17272 0.11176) (xy 0.19812 0.0762) (xy 0.2032 0.06604) (xy 0.20701 0.05715)
						(xy 0.21209 0.04699) (xy 0.2159 0.03683) (xy 0.21844 0.02667) (xy 0.22225 0.01524) (xy 0.22352 0.00508)
						(xy 0.22606 -0.00508) (xy 0.22733 -0.01651) (xy 0.22733 -0.02667) (xy 0.2286 -0.0381) (xy 0.22733 -0.04953)
						(xy 0.22733 -0.05969) (xy 0.22606 -0.07112) (xy 0.22352 -0.08128) (xy 0.22225 -0.09144) (xy 0.21844 -0.10287)
						(xy 0.2159 -0.11303) (xy 0.21209 -0.12319) (xy 0.20701 -0.13335) (xy 0.2032 -0.14224) (xy 0.19812 -0.1524)
						(xy 0.17272 -0.18796) (xy 0.1651 -0.19558) (xy 0.1651 -0.7366) (xy 0.16256 -0.76835) (xy 0.1524 -0.8001)
						(xy 0.13716 -0.82804) (xy 0.11684 -0.85344) (xy 0.09144 -0.87376) (xy 0.0635 -0.889) (xy 0.03175 -0.89916)
					)
					(width 0)
					(fill yes)
				)
			)
		)
		(pad "104" smd custom
			(at 1.649984 4.100068 180)
			(size 0.1143 0.1143)
			(layers "B.Cu" "B.Mask" "B.Paste")
			(net "M_B_MA4")
			(options
				(clearance outline)
				(anchor circle)
			)
			(primitives
				(gr_poly
					(pts
						(xy 0 -0.9017) (xy -0.03175 -0.89916) (xy -0.0635 -0.889) (xy -0.09144 -0.87376) (xy -0.11684 -0.85344)
						(xy -0.13716 -0.82804) (xy -0.1524 -0.8001) (xy -0.16256 -0.76835) (xy -0.1651 -0.7366) (xy -0.1651 -0.11938)
						(xy -0.17272 -0.11176) (xy -0.19812 -0.0762) (xy -0.2032 -0.06604) (xy -0.20701 -0.05715) (xy -0.21209 -0.04699)
						(xy -0.2159 -0.03683) (xy -0.21844 -0.02667) (xy -0.22225 -0.01524) (xy -0.22352 -0.00508) (xy -0.22606 0.00508)
						(xy -0.22733 0.01651) (xy -0.22733 0.02667) (xy -0.2286 0.0381) (xy -0.22733 0.04953) (xy -0.22733 0.05969)
						(xy -0.22606 0.07112) (xy -0.22352 0.08128) (xy -0.22225 0.09144) (xy -0.21844 0.10287) (xy -0.2159 0.11303)
						(xy -0.21209 0.12319) (xy -0.20701 0.13335) (xy -0.2032 0.14224) (xy -0.19812 0.1524) (xy -0.17272 0.18796)
						(xy -0.1651 0.19558) (xy -0.1651 0.7366) (xy -0.16256 0.76835) (xy -0.1524 0.8001) (xy -0.13716 0.82804)
						(xy -0.11684 0.85344) (xy -0.09144 0.87376) (xy -0.0635 0.889) (xy -0.03175 0.89916) (xy 0 0.9017)
						(xy 0.03175 0.89916) (xy 0.0635 0.889) (xy 0.09144 0.87376) (xy 0.11684 0.85344) (xy 0.13716 0.82804)
						(xy 0.1524 0.8001) (xy 0.16256 0.76835) (xy 0.1651 0.7366) (xy 0.1651 0.19685) (xy 0.17272 0.18923)
						(xy 0.17907 0.18034) (xy 0.18669 0.17145) (xy 0.19177 0.16256) (xy 0.19812 0.15367) (xy 0.20828 0.13335)
						(xy 0.21971 0.10287) (xy 0.22225 0.09271) (xy 0.22479 0.08128) (xy 0.22606 0.07112) (xy 0.2286 0.05969)
						(xy 0.2286 0.01651) (xy 0.22606 0.00508) (xy 0.22479 -0.00508) (xy 0.22225 -0.01651) (xy 0.21971 -0.02667)
						(xy 0.20828 -0.05715) (xy 0.19812 -0.07747) (xy 0.19177 -0.08636) (xy 0.18669 -0.09525) (xy 0.17907 -0.10414)
						(xy 0.17272 -0.11303) (xy 0.1651 -0.12065) (xy 0.1651 -0.7366) (xy 0.16256 -0.76835) (xy 0.1524 -0.8001)
						(xy 0.13716 -0.82804) (xy 0.11684 -0.85344) (xy 0.09144 -0.87376) (xy 0.0635 -0.889) (xy 0.03175 -0.89916)
					)
					(width 0)
					(fill yes)
				)
			)
		)
	)
)
